(kicad_pcb
	(version 20241229)
	(generator "pcbnew")
	(generator_version "9.0")
	(general
		(thickness 1.6296)
		(legacy_teardrops no)
	)
	(paper "A3")
	(title_block
		(title "Thunderbolt to 10GbE adapter")
		(date "2026-04-21")
		(rev "1.1.0")
		(company "Antmicro Ltd")
		(comment 1 "www.antmicro.com")
		(comment 9 "footprints 348-351 of 703")
	)
	(layers
		(0 "F.Cu" signal)
		(4 "In1.Cu" signal)
		(6 "In2.Cu" signal)
		(8 "In3.Cu" signal)
		(10 "In4.Cu" signal)
		(12 "In5.Cu" signal)
		(14 "In6.Cu" signal)
		(2 "B.Cu" signal)
		(9 "F.Adhes" user "F.Adhesive")
		(11 "B.Adhes" user "B.Adhesive")
		(13 "F.Paste" user)
		(15 "B.Paste" user)
		(5 "F.SilkS" user "F.Silkscreen")
		(7 "B.SilkS" user "B.Silkscreen")
		(1 "F.Mask" user)
		(3 "B.Mask" user)
		(17 "Dwgs.User" user "User.Drawings")
		(19 "Cmts.User" user "User.Comments")
		(21 "Eco1.User" user "User.Eco1")
		(23 "Eco2.User" user "User.Eco2")
		(25 "Edge.Cuts" user)
		(27 "Margin" user)
		(31 "F.CrtYd" user "F.Courtyard")
		(29 "B.CrtYd" user "B.Courtyard")
		(35 "F.Fab" user)
		(33 "B.Fab" user)
	)
	(footprint "antmicro-footprints:C_0402_1005Metric"
		(layer "F.Cu")
		(at 143.849999 109.150002)
		(descr "Capacitor SMD 0402")
		(tags "capacitor SMD 0402")
		(property "Reference" "C123"
			(at 15.349999 17.25 0)
			(layer "F.SilkS")
			(effects
				(font
					(size 0.7 0.7)
					(thickness 0.15)
				)
			)
		)
		(property "Value" "C_1u_25V_0402"
			(at -1.022927 2.155213 0)
			(layer "F.Fab")
			(effects
				(font
					(size 0.7 0.7)
					(thickness 0.15)
				)
				(justify left bottom)
			)
		)
		(property "Datasheet" "https://www.murata.com/products/productdetail?partno=GRM155R61E105KE11%23"
			(at 0 0 0)
			(layer "F.Fab")
			(hide yes)
			(effects
				(font
					(size 1.27 1.27)
					(thickness 0.15)
				)
			)
		)
		(property "Description" "SMD Multilayer Ceramic Capacitor, 1 µF, 25 V, 0402 [1005 Metric], ± 10%, X5R, GRM Series"
			(at 0 0 0)
			(layer "F.Fab")
			(hide yes)
			(effects
				(font
					(size 1.27 1.27)
					(thickness 0.15)
				)
			)
		)
		(property "MPN" "GRM155R61E105KE11J"
			(at 0 0 0)
			(unlocked yes)
			(layer "F.Fab")
			(hide yes)
			(effects
				(font
					(size 1 1)
					(thickness 0.15)
				)
			)
		)
		(property "Manufacturer" "Murata"
			(at 0 0 0)
			(unlocked yes)
			(layer "F.Fab")
			(hide yes)
			(effects
				(font
					(size 1 1)
					(thickness 0.15)
				)
			)
		)
		(property "License" "Apache-2.0"
			(at 0 0 0)
			(unlocked yes)
			(layer "F.Fab")
			(hide yes)
			(effects
				(font
					(size 1 1)
					(thickness 0.15)
				)
			)
		)
		(property "Author" "Antmicro"
			(at 0 0 0)
			(unlocked yes)
			(layer "F.Fab")
			(hide yes)
			(effects
				(font
					(size 1 1)
					(thickness 0.15)
				)
			)
		)
		(property "Val" "1u"
			(at 0 0 0)
			(unlocked yes)
			(layer "F.Fab")
			(hide yes)
			(effects
				(font
					(size 1 1)
					(thickness 0.15)
				)
			)
		)
		(property "Voltage" "25V"
			(at 0 0 0)
			(unlocked yes)
			(layer "F.Fab")
			(hide yes)
			(effects
				(font
					(size 1 1)
					(thickness 0.15)
				)
			)
		)
		(property "Dielectric" "X5R"
			(at 0 0 0)
			(unlocked yes)
			(layer "F.Fab")
			(hide yes)
			(effects
				(font
					(size 1 1)
					(thickness 0.15)
				)
			)
		)
		(sheetname "/X710 DCDC converters/")
		(sheetfile "DCDC_converters_X710.kicad_sch")
		(attr smd)
		(fp_rect
			(start -0.925 -0.47)
			(end 0.925 0.47)
			(stroke
				(width 0.05)
				(type default)
			)
			(fill no)
			(layer "F.CrtYd")
		)
		(fp_line
			(start -0.494 -0.25)
			(end 0.504 -0.25)
			(stroke
				(width 0.15)
				(type solid)
			)
			(layer "F.Fab")
		)
		(fp_line
			(start -0.494 0.248)
			(end -0.494 -0.25)
			(stroke
				(width 0.15)
				(type solid)
			)
			(layer "F.Fab")
		)
		(fp_line
			(start 0.504 -0.25)
			(end 0.504 0.248)
			(stroke
				(width 0.15)
				(type solid)
			)
			(layer "F.Fab")
		)
		(fp_line
			(start 0.504 0.248)
			(end -0.494 0.248)
			(stroke
				(width 0.15)
				(type solid)
			)
			(layer "F.Fab")
		)
		(fp_text user "Author: Antmicro"
			(at -0.939 3.399 0)
			(layer "F.Fab")
			(effects
				(font
					(size 0.7 0.7)
					(thickness 0.15)
				)
				(justify left bottom)
			)
		)
		(fp_text user "License: Apache-2.0"
			(at -0.939 5.799 0)
			(layer "F.Fab")
			(effects
				(font
					(size 0.7 0.7)
					(thickness 0.15)
				)
				(justify left bottom)
			)
		)
		(fp_text user "${REFERENCE}"
			(at -0.939 4.599 0)
			(layer "F.Fab")
			(effects
				(font
					(size 0.7 0.7)
					(thickness 0.15)
				)
				(justify left bottom)
			)
		)
		(pad "1" smd roundrect
			(at -0.48 0)
			(size 0.59 0.64)
			(layers "F.Cu" "F.Mask" "F.Paste")
			(roundrect_rratio 0.25)
			(net 23 "GND")
			(pintype "passive")
		)
		(pad "2" smd roundrect
			(at 0.48 0)
			(size 0.59 0.64)
			(layers "F.Cu" "F.Mask" "F.Paste")
			(roundrect_rratio 0.25)
			(net 116 "/X710 DCDC converters/DVDD_VCC")
			(pintype "passive")
		)
	)
	(footprint "antmicro-footprints:L_Coilcraft-XAL5030"
		(layer "F.Cu")
		(at 120.25 98.5)
		(property "Reference" "L1"
			(at -0.05 -3.5 0)
			(layer "F.SilkS")
			(effects
				(font
					(size 0.7 0.7)
					(thickness 0.15)
				)
			)
		)
		(property "Value" "L_2u2_9.7A_Coilcraft-XAL5030"
			(at 0 4.241 0)
			(layer "F.Fab")
			(effects
				(font
					(size 0.7 0.7)
					(thickness 0.15)
				)
				(justify left bottom)
			)
		)
		(property "Datasheet" "https://www.coilcraft.com/getmedia/49bc46c8-4b2c-45b9-9b6c-2eaa235ea698/xal50xx.pdf"
			(at 0 0 0)
			(layer "F.Fab")
			(hide yes)
			(effects
				(font
					(size 1.27 1.27)
					(thickness 0.15)
				)
			)
		)
		(property "Description" "Power Inductor (SMT), 2.2 µH, 9.7 A, Shielded, 9.2 A, XAL5030"
			(at 0 0 0)
			(layer "F.Fab")
			(hide yes)
			(effects
				(font
					(size 1.27 1.27)
					(thickness 0.15)
				)
			)
		)
		(property "Val" "2u2/9.7A"
			(at 0 0 0)
			(unlocked yes)
			(layer "F.Fab")
			(hide yes)
			(effects
				(font
					(size 1 1)
					(thickness 0.15)
				)
			)
		)
		(property "Manufacturer" "Coilcraft"
			(at 0 0 0)
			(unlocked yes)
			(layer "F.Fab")
			(hide yes)
			(effects
				(font
					(size 1 1)
					(thickness 0.15)
				)
			)
		)
		(property "MPN" "XAL5030-222MEC"
			(at 0 0 0)
			(unlocked yes)
			(layer "F.Fab")
			(hide yes)
			(effects
				(font
					(size 1 1)
					(thickness 0.15)
				)
			)
		)
		(property "ISat" "9.2 A"
			(at 0 0 0)
			(unlocked yes)
			(layer "F.Fab")
			(hide yes)
			(effects
				(font
					(size 1 1)
					(thickness 0.15)
				)
			)
		)
		(property "IMax" "9.7 A"
			(at 0 0 0)
			(unlocked yes)
			(layer "F.Fab")
			(hide yes)
			(effects
				(font
					(size 1 1)
					(thickness 0.15)
				)
			)
		)
		(property "Size" "5.28x5.48"
			(at 0 0 0)
			(unlocked yes)
			(layer "F.Fab")
			(hide yes)
			(effects
				(font
					(size 1 1)
					(thickness 0.15)
				)
			)
		)
		(property "Author" "Antmicro"
			(at 0 0 0)
			(unlocked yes)
			(layer "F.Fab")
			(hide yes)
			(effects
				(font
					(size 1 1)
					(thickness 0.15)
				)
			)
		)
		(property "License" "Apache-2.0"
			(at 0 0 0)
			(unlocked yes)
			(layer "F.Fab")
			(hide yes)
			(effects
				(font
					(size 1 1)
					(thickness 0.15)
				)
			)
		)
		(sheetname "/PD and TB DC-DC/")
		(sheetfile "PD_and_TB_DC_DC.kicad_sch")
		(attr smd)
		(fp_line
			(start -2.74 -2.84)
			(end 2.74 -2.84)
			(stroke
				(width 0.15)
				(type solid)
			)
			(layer "F.SilkS")
		)
		(fp_line
			(start -2.74 2.84)
			(end -2.74 -2.84)
			(stroke
				(width 0.15)
				(type solid)
			)
			(layer "F.SilkS")
		)
		(fp_line
			(start -2.74 2.84)
			(end 2.74 2.84)
			(stroke
				(width 0.15)
				(type solid)
			)
			(layer "F.SilkS")
		)
		(fp_line
			(start 2.74 2.84)
			(end 2.74 -2.84)
			(stroke
				(width 0.15)
				(type solid)
			)
			(layer "F.SilkS")
		)
		(fp_rect
			(start -2.89 -2.99)
			(end 2.89 2.99)
			(stroke
				(width 0.05)
				(type solid)
			)
			(fill no)
			(layer "F.CrtYd")
		)
		(fp_line
			(start -2.74 -2.84)
			(end 2.74 -2.84)
			(stroke
				(width 0.15)
				(type solid)
			)
			(layer "F.Fab")
		)
		(fp_line
			(start -2.74 2.84)
			(end -2.74 -2.84)
			(stroke
				(width 0.15)
				(type solid)
			)
			(layer "F.Fab")
		)
		(fp_line
			(start 2.74 -2.84)
			(end 2.74 2.84)
			(stroke
				(width 0.15)
				(type solid)
			)
			(layer "F.Fab")
		)
		(fp_line
			(start 2.74 2.84)
			(end -2.74 2.84)
			(stroke
				(width 0.15)
				(type solid)
			)
			(layer "F.Fab")
		)
		(fp_text user "License: Apache-2.0"
			(at -2.89 6.241 0)
			(layer "F.Fab")
			(effects
				(font
					(size 0.7 0.7)
					(thickness 0.15)
				)
				(justify left bottom)
			)
		)
		(fp_text user "Author: Antmicro"
			(at -2.89 7.441 0)
			(layer "F.Fab")
			(effects
				(font
					(size 0.7 0.7)
					(thickness 0.15)
				)
				(justify left bottom)
			)
		)
		(fp_text user "${REFERENCE}"
			(at -2.89 8.641 0)
			(layer "F.Fab")
			(effects
				(font
					(size 0.7 0.7)
					(thickness 0.15)
				)
				(justify left bottom)
			)
		)
		(pad "1" smd roundrect
			(at -1.655 0)
			(size 1.18 4.7)
			(layers "F.Cu" "F.Mask" "F.Paste")
			(roundrect_rratio 0.1)
			(net 163 "Net-(U2-SW)")
			(pintype "passive")
		)
		(pad "2" smd roundrect
			(at 1.655 0)
			(size 1.18 4.7)
			(layers "F.Cu" "F.Mask" "F.Paste")
			(roundrect_rratio 0.1)
			(net 399 "Net-(D4-A)")
			(pintype "passive")
		)
	)
	(footprint "antmicro-footprints:R_0402_1005Metric"
		(layer "F.Cu")
		(at 117 65.5 180)
		(descr "Resistor SMD 0402")
		(tags "resistor SMD 0402")
		(property "Reference" "R131"
			(at -3 -1.4 180)
			(layer "F.SilkS")
			(effects
				(font
					(size 0.7 0.7)
					(thickness 0.15)
				)
				(justify left bottom)
			)
		)
		(property "Value" "R_1k_0402"
			(at -1.011843 1.772047 180)
			(layer "F.Fab")
			(effects
				(font
					(size 0.7 0.7)
					(thickness 0.15)
				)
				(justify left bottom)
			)
		)
		(property "Datasheet" "https://www.bourns.com/docs/product-datasheets/cr.pdf"
			(at 0 0 180)
			(layer "F.Fab")
			(hide yes)
			(effects
				(font
					(size 1.27 1.27)
					(thickness 0.15)
				)
			)
		)
		(property "Description" "SMD Chip Resistor, 1 kohm, ± 1%, 63 mW, 0402 [1005 Metric], Thick Film, General Purpose"
			(at 0 0 180)
			(layer "F.Fab")
			(hide yes)
			(effects
				(font
					(size 1.27 1.27)
					(thickness 0.15)
				)
			)
		)
		(property "MPN" "CR0402-FX-1001GLF"
			(at 0 0 180)
			(unlocked yes)
			(layer "F.Fab")
			(hide yes)
			(effects
				(font
					(size 1 1)
					(thickness 0.15)
				)
			)
		)
		(property "Manufacturer" "Bourns"
			(at 0 0 180)
			(unlocked yes)
			(layer "F.Fab")
			(hide yes)
			(effects
				(font
					(size 1 1)
					(thickness 0.15)
				)
			)
		)
		(property "License" "Apache-2.0"
			(at 0 0 180)
			(unlocked yes)
			(layer "F.Fab")
			(hide yes)
			(effects
				(font
					(size 1 1)
					(thickness 0.15)
				)
			)
		)
		(property "Author" "Antmicro"
			(at 0 0 180)
			(unlocked yes)
			(layer "F.Fab")
			(hide yes)
			(effects
				(font
					(size 1 1)
					(thickness 0.15)
				)
			)
		)
		(property "Val" "1k"
			(at 0 0 180)
			(unlocked yes)
			(layer "F.Fab")
			(hide yes)
			(effects
				(font
					(size 1 1)
					(thickness 0.15)
				)
			)
		)
		(property "Tolerance" "1%"
			(at 0 0 180)
			(unlocked yes)
			(layer "F.Fab")
			(hide yes)
			(effects
				(font
					(size 1 1)
					(thickness 0.15)
				)
			)
		)
		(sheetname "/X710-AT2 RSVD/")
		(sheetfile "x710-at2-rsvd.kicad_sch")
		(attr smd)
		(fp_rect
			(start -0.925 -0.47)
			(end 0.925 0.47)
			(stroke
				(width 0.05)
				(type default)
			)
			(fill no)
			(layer "F.CrtYd")
		)
		(fp_rect
			(start -0.5 -0.25)
			(end 0.5 0.25)
			(stroke
				(width 0.15)
				(type solid)
			)
			(fill no)
			(layer "F.Fab")
		)
		(fp_text user "Author: Antmicro"
			(at -0.95 4.169 180)
			(layer "F.Fab")
			(effects
				(font
					(size 0.7 0.7)
					(thickness 0.15)
				)
				(justify left bottom)
			)
		)
		(fp_text user "${REFERENCE}"
			(at -0.95 3.168 180)
			(layer "F.Fab")
			(effects
				(font
					(size 0.7 0.7)
					(thickness 0.15)
				)
				(justify left bottom)
			)
		)
		(fp_text user "License: Apache-2.0"
			(at -0.95 5.169 180)
			(layer "F.Fab")
			(effects
				(font
					(size 0.7 0.7)
					(thickness 0.15)
				)
				(justify left bottom)
			)
		)
		(pad "1" smd roundrect
			(at -0.48 0 180)
			(size 0.59 0.64)
			(layers "F.Cu" "F.Mask" "F.Paste")
			(roundrect_rratio 0.25)
			(net 89 "/X710-AT2 RSVD/DEBUG_Y20")
			(pintype "passive")
		)
		(pad "2" smd roundrect
			(at 0.48 0 180)
			(size 0.59 0.64)
			(layers "F.Cu" "F.Mask" "F.Paste")
			(roundrect_rratio 0.25)
			(net 86 "/X710-AT2 RSVD/DEBUG_EN")
			(pintype "passive")
		)
	)
	(footprint "antmicro-footprints:C_0805_2012Metric"
		(layer "F.Cu")
		(at 151.1 56.8 -90)
		(descr "Capacitor SMD 0805")
		(tags "capacitor SMD 0805")
		(property "Reference" "C320"
			(at 4.6 -0.65 270)
			(layer "F.SilkS")
			(effects
				(font
					(size 0.7 0.7)
					(thickness 0.15)
				)
				(justify left bottom)
			)
		)
		(property "Value" "C_22u_25V_0805"
			(at -2.055717 1.963152 270)
			(layer "F.Fab")
			(effects
				(font
					(size 0.7 0.7)
					(thickness 0.15)
				)
				(justify left bottom)
			)
		)
		(property "Datasheet" "https://product.samsungsem.com/mlcc/CL21A226MAYNNN.do"
			(at 0 0 270)
			(layer "F.Fab")
			(hide yes)
			(effects
				(font
					(size 1.27 1.27)
					(thickness 0.15)
				)
			)
		)
		(property "Description" "SMT Multilayer Ceramic Capacitor, 22uF, +/-20%, 25V, X5R, 0805 [2012 Metric]"
			(at 0 0 270)
			(layer "F.Fab")
			(hide yes)
			(effects
				(font
					(size 1.27 1.27)
					(thickness 0.15)
				)
			)
		)
		(property "MPN" "CL21A226MAYNNNE"
			(at 0 0 270)
			(unlocked yes)
			(layer "F.Fab")
			(hide yes)
			(effects
				(font
					(size 1 1)
					(thickness 0.15)
				)
			)
		)
		(property "Manufacturer" "Samsung Electro-Mechanics"
			(at 0 0 270)
			(unlocked yes)
			(layer "F.Fab")
			(hide yes)
			(effects
				(font
					(size 1 1)
					(thickness 0.15)
				)
			)
		)
		(property "License" "Apache-2.0"
			(at 0 0 270)
			(unlocked yes)
			(layer "F.Fab")
			(hide yes)
			(effects
				(font
					(size 1 1)
					(thickness 0.15)
				)
			)
		)
		(property "Author" "Antmicro"
			(at 0 0 270)
			(unlocked yes)
			(layer "F.Fab")
			(hide yes)
			(effects
				(font
					(size 1 1)
					(thickness 0.15)
				)
			)
		)
		(property "Val" "22u"
			(at 0 0 270)
			(unlocked yes)
			(layer "F.Fab")
			(hide yes)
			(effects
				(font
					(size 1 1)
					(thickness 0.15)
				)
			)
		)
		(property "Voltage" "25V"
			(at 0 0 270)
			(unlocked yes)
			(layer "F.Fab")
			(hide yes)
			(effects
				(font
					(size 1 1)
					(thickness 0.15)
				)
			)
		)
		(property "Dielectric" "X5R"
			(at 0 0 270)
			(unlocked yes)
			(layer "F.Fab")
			(hide yes)
			(effects
				(font
					(size 1 1)
					(thickness 0.15)
				)
			)
		)
		(property "Public" "False"
			(at 0 0 270)
			(unlocked yes)
			(layer "F.Fab")
			(hide yes)
			(effects
				(font
					(size 1 1)
					(thickness 0.15)
				)
			)
		)
		(sheetname "/Power input/")
		(sheetfile "power_input.kicad_sch")
		(attr smd)
		(fp_line
			(start -0.3 0.7)
			(end 0.3 0.7)
			(stroke
				(width 0.15)
				(type solid)
			)
			(layer "F.SilkS")
		)
		(fp_line
			(start -0.3 -0.7)
			(end 0.3 -0.7)
			(stroke
				(width 0.15)
				(type solid)
			)
			(layer "F.SilkS")
		)
		(fp_rect
			(start 1.95 -0.9)
			(end -1.95 0.9)
			(stroke
				(width 0.05)
				(type default)
			)
			(fill no)
			(layer "F.CrtYd")
		)
		(fp_rect
			(start -0.95 -0.675)
			(end 0.95 0.675)
			(stroke
				(width 0.15)
				(type solid)
			)
			(fill no)
			(layer "F.Fab")
		)
		(fp_text user "${REFERENCE}"
			(at -1.9 3.947 270)
			(layer "F.Fab")
			(effects
				(font
					(size 0.7 0.7)
					(thickness 0.15)
				)
				(justify left bottom)
			)
		)
		(fp_text user "License: Apache-2.0"
			(at -1.9 4.947 270)
			(layer "F.Fab")
			(effects
				(font
					(size 0.7 0.7)
					(thickness 0.15)
				)
				(justify left bottom)
			)
		)
		(fp_text user "Author: Antmicro"
			(at -1.9 5.947 270)
			(layer "F.Fab")
			(effects
				(font
					(size 0.7 0.7)
					(thickness 0.15)
				)
				(justify left bottom)
			)
		)
		(pad "1" smd roundrect
			(at -1.1 0 270)
			(size 1.2 1.3)
			(layers "F.Cu" "F.Mask" "F.Paste")
			(roundrect_rratio 0.25)
			(net 23 "GND")
			(pintype "passive")
		)
		(pad "2" smd roundrect
			(at 1.1 0 270)
			(size 1.2 1.3)
			(layers "F.Cu" "F.Mask" "F.Paste")
			(roundrect_rratio 0.25)
			(net 349 "/Power input/5V_OUT")
			(pintype "passive")
		)
	)
)
